(kicad_pcb
	(version 20260206)
	(generator "pcbnew")
	(generator_version "10.0")
	(general
		(thickness 1.6)
		(legacy_teardrops no)
	)
	(paper "A4")
	(title_block
		(title "01162023_DA0F0TEBIF0_F0T_Expander_BD_F_brd_V02_OCP.brd")
		(comment 1 "Grand Teton / footprint 4451 of 9728 (PEX3), pads 2000-2119 of 2397")
	)
	(layers
		(0 "F.Cu" signal "TOP")
		(4 "In1.Cu" signal "GND")
		(6 "In2.Cu" signal "VCC")
		(8 "In3.Cu" signal "VCC1")
		(10 "In4.Cu" signal "GND1")
		(12 "In5.Cu" signal "IN1")
		(14 "In6.Cu" signal "GND2")
		(16 "In7.Cu" signal "IN2")
		(18 "In8.Cu" signal "GND3")
		(20 "In9.Cu" signal "IN3")
		(22 "In10.Cu" signal "GND4")
		(24 "In11.Cu" signal "IN4")
		(26 "In12.Cu" signal "GND5")
		(28 "In13.Cu" signal "IN5")
		(30 "In14.Cu" signal "GND6")
		(32 "In15.Cu" signal "IN6")
		(34 "In16.Cu" signal "GND7")
		(2 "B.Cu" signal "BOTTOM")
		(9 "F.Adhes" user "F.Adhesive")
		(11 "B.Adhes" user "B.Adhesive")
		(13 "F.Paste" user "Package Geometry/Pastemask Top")
		(15 "B.Paste" user "Package Geometry/Pastemask Bottom")
		(5 "F.SilkS" user "Ref Des/Silkscreen Top")
		(7 "B.SilkS" user "Ref Des/Silkscreen Bottom")
		(1 "F.Mask" user "Board Geometry/Soldermask Top")
		(3 "B.Mask" user "Board Geometry/Soldermask Bottom")
		(17 "Dwgs.User" user "User.Drawings")
		(19 "Cmts.User" user "User.Comments")
		(21 "Eco1.User" user "User.Eco1")
		(23 "Eco2.User" user "User.Eco2")
		(25 "Edge.Cuts" user "Board Geometry/Outline")
		(27 "Margin" user)
		(31 "F.CrtYd" user "Package Geometry/Place Bound Top")
		(29 "B.CrtYd" user "Package Geometry/Place Bound Bottom")
		(35 "F.Fab" user "Ref Des/Assembly Top")
		(33 "B.Fab" user "Ref Des/Assembly Bottom")
	)
	(footprint ""
		(layer "F.Cu")
		(at 407.949908 -295.89984)
		(property "Reference" "PEX3"
			(at -3.358642 35.5727 0)
			(unlocked yes)
			(layer "F.SilkS")
			(effects
				(font
					(size 2.032 1.524)
					(thickness 0.1524)
				)
				(justify left)
			)
		)
		(property "Value" ""
			(at 0 0 0)
			(layer "F.Fab")
			(effects
				(font
					(size 1.27 1.27)
				)
			)
		)
		(duplicate_pad_numbers_are_jumpers no)
		(pad "M44" smd circle
			(at 18.050002 -12.349988)
			(size 0.4572 0.4572)
			(layers "F.Cu" "F.Mask" "F.Paste")
			(net "GND")
		)
		(pad "M45" smd circle
			(at 18.999962 -12.349988)
			(size 0.4572 0.4572)
			(layers "F.Cu" "F.Mask" "F.Paste")
			(net "GND")
		)
		(pad "M46" smd circle
			(at 19.949922 -12.349988)
			(size 0.4572 0.4572)
			(layers "F.Cu" "F.Mask" "F.Paste")
			(net "GND")
		)
		(pad "M47" smd circle
			(at 20.899882 -12.349988)
			(size 0.4572 0.4572)
			(layers "F.Cu" "F.Mask" "F.Paste")
			(net "GND")
		)
		(pad "M48" smd circle
			(at 21.850096 -12.349988)
			(size 0.4572 0.4572)
			(layers "F.Cu" "F.Mask" "F.Paste")
			(net "P5E_PEX3_STN4_RX_DP<68>")
		)
		(pad "M49" smd circle
			(at 22.800056 -12.349988)
			(size 0.4572 0.4572)
			(layers "F.Cu" "F.Mask" "F.Paste")
			(net "P5E_PEX3_STN4_RX_DN<68>")
		)
		(pad "N1" smd circle
			(at -22.800056 -11.400028)
			(size 0.4572 0.4572)
			(layers "F.Cu" "F.Mask" "F.Paste")
			(net "GND")
		)
		(pad "N2" smd circle
			(at -21.850096 -11.400028)
			(size 0.4572 0.4572)
			(layers "F.Cu" "F.Mask" "F.Paste")
			(net "GND")
		)
		(pad "N3" smd circle
			(at -20.899882 -11.400028)
			(size 0.4572 0.4572)
			(layers "F.Cu" "F.Mask" "F.Paste")
			(net "P5E_PEX3_STN7_RX_DN<118>")
		)
		(pad "N4" smd circle
			(at -19.949922 -11.400028)
			(size 0.4572 0.4572)
			(layers "F.Cu" "F.Mask" "F.Paste")
			(net "P5E_PEX3_STN7_RX_DP<118>")
		)
		(pad "N5" smd circle
			(at -18.999962 -11.400028)
			(size 0.4572 0.4572)
			(layers "F.Cu" "F.Mask" "F.Paste")
			(net "GND")
		)
		(pad "N6" smd circle
			(at -18.050002 -11.400028)
			(size 0.4572 0.4572)
			(layers "F.Cu" "F.Mask" "F.Paste")
			(net "P5E_PEX3_STN7_TX_DN<118>")
		)
		(pad "N7" smd circle
			(at -17.100042 -11.400028)
			(size 0.4572 0.4572)
			(layers "F.Cu" "F.Mask" "F.Paste")
			(net "P5E_PEX3_STN7_TX_DP<118>")
		)
		(pad "N8" smd circle
			(at -16.150082 -11.400028)
			(size 0.4572 0.4572)
			(layers "F.Cu" "F.Mask" "F.Paste")
			(net "GND")
		)
		(pad "N9" smd circle
			(at -15.200122 -11.400028)
			(size 0.4572 0.4572)
			(layers "F.Cu" "F.Mask" "F.Paste")
			(net "GND")
		)
		(pad "N10" smd circle
			(at -14.249908 -11.400028)
			(size 0.4572 0.4572)
			(layers "F.Cu" "F.Mask" "F.Paste")
			(net "GND")
		)
		(pad "N11" smd circle
			(at -13.299948 -11.400028)
			(size 0.4572 0.4572)
			(layers "F.Cu" "F.Mask" "F.Paste")
			(net "GND")
		)
		(pad "N12" smd circle
			(at -12.349988 -11.400028)
			(size 0.4572 0.4572)
			(layers "F.Cu" "F.Mask" "F.Paste")
			(net "GND")
		)
		(pad "N13" smd circle
			(at -11.400028 -11.400028)
			(size 0.4572 0.4572)
			(layers "F.Cu" "F.Mask" "F.Paste")
			(net "GND")
		)
		(pad "N14" smd circle
			(at -10.450068 -11.400028)
			(size 0.4572 0.4572)
			(layers "F.Cu" "F.Mask" "F.Paste")
			(net "GND")
		)
		(pad "N15" smd circle
			(at -9.500108 -11.400028)
			(size 0.4572 0.4572)
			(layers "F.Cu" "F.Mask" "F.Paste")
			(net "GND")
		)
		(pad "N16" smd circle
			(at -8.549894 -11.400028)
			(size 0.4572 0.4572)
			(layers "F.Cu" "F.Mask" "F.Paste")
			(net "GND")
		)
		(pad "N17" smd circle
			(at -7.599934 -11.400028)
			(size 0.4572 0.4572)
			(layers "F.Cu" "F.Mask" "F.Paste")
			(net "GND")
		)
		(pad "N18" smd circle
			(at -6.649974 -11.400028)
			(size 0.4572 0.4572)
			(layers "F.Cu" "F.Mask" "F.Paste")
			(net "GND")
		)
		(pad "N19" smd circle
			(at -5.700014 -11.400028)
			(size 0.4572 0.4572)
			(layers "F.Cu" "F.Mask" "F.Paste")
			(net "GND")
		)
		(pad "N20" smd circle
			(at -4.750054 -11.400028)
			(size 0.4572 0.4572)
			(layers "F.Cu" "F.Mask" "F.Paste")
			(net "GND")
		)
		(pad "N21" smd circle
			(at -3.800094 -11.400028)
			(size 0.4572 0.4572)
			(layers "F.Cu" "F.Mask" "F.Paste")
			(net "GND")
		)
		(pad "N22" smd circle
			(at -2.84988 -11.400028)
			(size 0.4572 0.4572)
			(layers "F.Cu" "F.Mask" "F.Paste")
			(net "GND")
		)
		(pad "N23" smd circle
			(at -1.89992 -11.400028)
			(size 0.4572 0.4572)
			(layers "F.Cu" "F.Mask" "F.Paste")
			(net "GND")
		)
		(pad "N24" smd circle
			(at -0.94996 -11.400028)
			(size 0.4572 0.4572)
			(layers "F.Cu" "F.Mask" "F.Paste")
			(net "GND")
		)
		(pad "N25" smd circle
			(at 0 -11.400028)
			(size 0.4572 0.4572)
			(layers "F.Cu" "F.Mask" "F.Paste")
			(net "GND")
		)
		(pad "N26" smd circle
			(at 0.94996 -11.400028)
			(size 0.4572 0.4572)
			(layers "F.Cu" "F.Mask" "F.Paste")
			(net "GND")
		)
		(pad "N27" smd circle
			(at 1.89992 -11.400028)
			(size 0.4572 0.4572)
			(layers "F.Cu" "F.Mask" "F.Paste")
			(net "GND")
		)
		(pad "N28" smd circle
			(at 2.84988 -11.400028)
			(size 0.4572 0.4572)
			(layers "F.Cu" "F.Mask" "F.Paste")
			(net "GND")
		)
		(pad "N29" smd circle
			(at 3.800094 -11.400028)
			(size 0.4572 0.4572)
			(layers "F.Cu" "F.Mask" "F.Paste")
			(net "GND")
		)
		(pad "N30" smd circle
			(at 4.750054 -11.400028)
			(size 0.4572 0.4572)
			(layers "F.Cu" "F.Mask" "F.Paste")
			(net "GND")
		)
		(pad "N31" smd circle
			(at 5.700014 -11.400028)
			(size 0.4572 0.4572)
			(layers "F.Cu" "F.Mask" "F.Paste")
			(net "GND")
		)
		(pad "N32" smd circle
			(at 6.649974 -11.400028)
			(size 0.4572 0.4572)
			(layers "F.Cu" "F.Mask" "F.Paste")
			(net "GND")
		)
		(pad "N33" smd circle
			(at 7.599934 -11.400028)
			(size 0.4572 0.4572)
			(layers "F.Cu" "F.Mask" "F.Paste")
			(net "GND")
		)
		(pad "N34" smd circle
			(at 8.549894 -11.400028)
			(size 0.4572 0.4572)
			(layers "F.Cu" "F.Mask" "F.Paste")
			(net "GND")
		)
		(pad "N35" smd circle
			(at 9.500108 -11.400028)
			(size 0.4572 0.4572)
			(layers "F.Cu" "F.Mask" "F.Paste")
			(net "GND")
		)
		(pad "N36" smd circle
			(at 10.450068 -11.400028)
			(size 0.4572 0.4572)
			(layers "F.Cu" "F.Mask" "F.Paste")
			(net "GND")
		)
		(pad "N37" smd circle
			(at 11.400028 -11.400028)
			(size 0.4572 0.4572)
			(layers "F.Cu" "F.Mask" "F.Paste")
			(net "GND")
		)
		(pad "N38" smd circle
			(at 12.349988 -11.400028)
			(size 0.4572 0.4572)
			(layers "F.Cu" "F.Mask" "F.Paste")
			(net "SMB_PEX3_SLAVE_SCL")
		)
		(pad "N39" smd circle
			(at 13.299948 -11.400028)
			(size 0.4572 0.4572)
			(layers "F.Cu" "F.Mask" "F.Paste")
			(net "Net_5460")
		)
		(pad "N40" smd circle
			(at 14.249908 -11.400028)
			(size 0.4572 0.4572)
			(layers "F.Cu" "F.Mask" "F.Paste")
			(net "GND")
		)
		(pad "N41" smd circle
			(at 15.200122 -11.400028)
			(size 0.4572 0.4572)
			(layers "F.Cu" "F.Mask" "F.Paste")
			(net "GND")
		)
		(pad "N42" smd circle
			(at 16.150082 -11.400028)
			(size 0.4572 0.4572)
			(layers "F.Cu" "F.Mask" "F.Paste")
			(net "GND")
		)
		(pad "N43" smd circle
			(at 17.100042 -11.400028)
			(size 0.4572 0.4572)
			(layers "F.Cu" "F.Mask" "F.Paste")
			(net "P5E_PEX3_STN4_TX_DP<67>")
		)
		(pad "N44" smd circle
			(at 18.050002 -11.400028)
			(size 0.4572 0.4572)
			(layers "F.Cu" "F.Mask" "F.Paste")
			(net "P5E_PEX3_STN4_TX_DN<67>")
		)
		(pad "N45" smd circle
			(at 18.999962 -11.400028)
			(size 0.4572 0.4572)
			(layers "F.Cu" "F.Mask" "F.Paste")
			(net "GND")
		)
		(pad "N46" smd circle
			(at 19.949922 -11.400028)
			(size 0.4572 0.4572)
			(layers "F.Cu" "F.Mask" "F.Paste")
			(net "P5E_PEX3_STN4_RX_DP<67>")
		)
		(pad "N47" smd circle
			(at 20.899882 -11.400028)
			(size 0.4572 0.4572)
			(layers "F.Cu" "F.Mask" "F.Paste")
			(net "P5E_PEX3_STN4_RX_DN<67>")
		)
		(pad "N48" smd circle
			(at 21.850096 -11.400028)
			(size 0.4572 0.4572)
			(layers "F.Cu" "F.Mask" "F.Paste")
			(net "GND")
		)
		(pad "N49" smd circle
			(at 22.800056 -11.400028)
			(size 0.4572 0.4572)
			(layers "F.Cu" "F.Mask" "F.Paste")
			(net "GND")
		)
		(pad "P1" smd circle
			(at -22.800056 -10.450068)
			(size 0.4572 0.4572)
			(layers "F.Cu" "F.Mask" "F.Paste")
			(net "P5E_PEX3_STN7_RX_DN<117>")
		)
		(pad "P2" smd circle
			(at -21.850096 -10.450068)
			(size 0.4572 0.4572)
			(layers "F.Cu" "F.Mask" "F.Paste")
			(net "P5E_PEX3_STN7_RX_DP<117>")
		)
		(pad "P3" smd circle
			(at -20.899882 -10.450068)
			(size 0.4572 0.4572)
			(layers "F.Cu" "F.Mask" "F.Paste")
			(net "GND")
		)
		(pad "P4" smd circle
			(at -19.949922 -10.450068)
			(size 0.4572 0.4572)
			(layers "F.Cu" "F.Mask" "F.Paste")
			(net "GND")
		)
		(pad "P5" smd circle
			(at -18.999962 -10.450068)
			(size 0.4572 0.4572)
			(layers "F.Cu" "F.Mask" "F.Paste")
			(net "GND")
		)
		(pad "P6" smd circle
			(at -18.050002 -10.450068)
			(size 0.4572 0.4572)
			(layers "F.Cu" "F.Mask" "F.Paste")
			(net "GND")
		)
		(pad "P7" smd circle
			(at -17.100042 -10.450068)
			(size 0.4572 0.4572)
			(layers "F.Cu" "F.Mask" "F.Paste")
			(net "GND")
		)
		(pad "P8" smd circle
			(at -16.150082 -10.450068)
			(size 0.4572 0.4572)
			(layers "F.Cu" "F.Mask" "F.Paste")
			(net "P5E_PEX3_STN7_TX_DN<117>")
		)
		(pad "P9" smd circle
			(at -15.200122 -10.450068)
			(size 0.4572 0.4572)
			(layers "F.Cu" "F.Mask" "F.Paste")
			(net "P5E_PEX3_STN7_TX_DP<117>")
		)
		(pad "P10" smd circle
			(at -14.249908 -10.450068)
			(size 0.4572 0.4572)
			(layers "F.Cu" "F.Mask" "F.Paste")
			(net "GND")
		)
		(pad "P11" smd circle
			(at -13.299948 -10.450068)
			(size 0.4572 0.4572)
			(layers "F.Cu" "F.Mask" "F.Paste")
			(net "GND")
		)
		(pad "P12" smd circle
			(at -12.349988 -10.450068)
			(size 0.4572 0.4572)
			(layers "F.Cu" "F.Mask" "F.Paste")
			(net "GND")
		)
		(pad "P13" smd circle
			(at -11.400028 -10.450068)
			(size 0.4572 0.4572)
			(layers "F.Cu" "F.Mask" "F.Paste")
			(net "GND")
		)
		(pad "P14" smd circle
			(at -10.450068 -10.450068)
			(size 0.4572 0.4572)
			(layers "F.Cu" "F.Mask" "F.Paste")
			(net "GND")
		)
		(pad "P15" smd circle
			(at -9.500108 -10.450068)
			(size 0.4572 0.4572)
			(layers "F.Cu" "F.Mask" "F.Paste")
			(net "GND")
		)
		(pad "P16" smd circle
			(at -8.549894 -10.450068)
			(size 0.4572 0.4572)
			(layers "F.Cu" "F.Mask" "F.Paste")
			(net "GND")
		)
		(pad "P17" smd circle
			(at -7.599934 -10.450068)
			(size 0.4572 0.4572)
			(layers "F.Cu" "F.Mask" "F.Paste")
			(net "GND")
		)
		(pad "P18" smd circle
			(at -6.649974 -10.450068)
			(size 0.4572 0.4572)
			(layers "F.Cu" "F.Mask" "F.Paste")
			(net "GND")
		)
		(pad "P19" smd circle
			(at -5.700014 -10.450068)
			(size 0.4572 0.4572)
			(layers "F.Cu" "F.Mask" "F.Paste")
			(net "GND")
		)
		(pad "P20" smd circle
			(at -4.750054 -10.450068)
			(size 0.4572 0.4572)
			(layers "F.Cu" "F.Mask" "F.Paste")
			(net "GND")
		)
		(pad "P21" smd circle
			(at -3.800094 -10.450068)
			(size 0.4572 0.4572)
			(layers "F.Cu" "F.Mask" "F.Paste")
			(net "GND")
		)
		(pad "P22" smd circle
			(at -2.84988 -10.450068)
			(size 0.4572 0.4572)
			(layers "F.Cu" "F.Mask" "F.Paste")
			(net "GND")
		)
		(pad "P23" smd circle
			(at -1.89992 -10.450068)
			(size 0.4572 0.4572)
			(layers "F.Cu" "F.Mask" "F.Paste")
			(net "GND")
		)
		(pad "P24" smd circle
			(at -0.94996 -10.450068)
			(size 0.4572 0.4572)
			(layers "F.Cu" "F.Mask" "F.Paste")
			(net "GND")
		)
		(pad "P25" smd circle
			(at 0 -10.450068)
			(size 0.4572 0.4572)
			(layers "F.Cu" "F.Mask" "F.Paste")
			(net "GND")
		)
		(pad "P26" smd circle
			(at 0.94996 -10.450068)
			(size 0.4572 0.4572)
			(layers "F.Cu" "F.Mask" "F.Paste")
			(net "GND")
		)
		(pad "P27" smd circle
			(at 1.89992 -10.450068)
			(size 0.4572 0.4572)
			(layers "F.Cu" "F.Mask" "F.Paste")
			(net "GND")
		)
		(pad "P28" smd circle
			(at 2.84988 -10.450068)
			(size 0.4572 0.4572)
			(layers "F.Cu" "F.Mask" "F.Paste")
			(net "GND")
		)
		(pad "P29" smd circle
			(at 3.800094 -10.450068)
			(size 0.4572 0.4572)
			(layers "F.Cu" "F.Mask" "F.Paste")
			(net "GND")
		)
		(pad "P30" smd circle
			(at 4.750054 -10.450068)
			(size 0.4572 0.4572)
			(layers "F.Cu" "F.Mask" "F.Paste")
			(net "GND")
		)
		(pad "P31" smd circle
			(at 5.700014 -10.450068)
			(size 0.4572 0.4572)
			(layers "F.Cu" "F.Mask" "F.Paste")
			(net "GND")
		)
		(pad "P32" smd circle
			(at 6.649974 -10.450068)
			(size 0.4572 0.4572)
			(layers "F.Cu" "F.Mask" "F.Paste")
			(net "GND")
		)
		(pad "P33" smd circle
			(at 7.599934 -10.450068)
			(size 0.4572 0.4572)
			(layers "F.Cu" "F.Mask" "F.Paste")
			(net "GND")
		)
		(pad "P34" smd circle
			(at 8.549894 -10.450068)
			(size 0.4572 0.4572)
			(layers "F.Cu" "F.Mask" "F.Paste")
			(net "GND")
		)
		(pad "P35" smd circle
			(at 9.500108 -10.450068)
			(size 0.4572 0.4572)
			(layers "F.Cu" "F.Mask" "F.Paste")
			(net "GND")
		)
		(pad "P36" smd circle
			(at 10.450068 -10.450068)
			(size 0.4572 0.4572)
			(layers "F.Cu" "F.Mask" "F.Paste")
			(net "Net_538")
		)
		(pad "P37" smd circle
			(at 11.400028 -10.450068)
			(size 0.4572 0.4572)
			(layers "F.Cu" "F.Mask" "F.Paste")
			(net "GND")
		)
		(pad "P38" smd circle
			(at 12.349988 -10.450068)
			(size 0.4572 0.4572)
			(layers "F.Cu" "F.Mask" "F.Paste")
			(net "RST_PEX3_S3_PERST_R_N")
		)
		(pad "P39" smd circle
			(at 13.299948 -10.450068)
			(size 0.4572 0.4572)
			(layers "F.Cu" "F.Mask" "F.Paste")
			(net "RST_PEX3_S1_PERST_R_N")
		)
		(pad "P40" smd circle
			(at 14.249908 -10.450068)
			(size 0.4572 0.4572)
			(layers "F.Cu" "F.Mask" "F.Paste")
			(net "GND")
		)
		(pad "P41" smd circle
			(at 15.200122 -10.450068)
			(size 0.4572 0.4572)
			(layers "F.Cu" "F.Mask" "F.Paste")
			(net "P5E_PEX3_STN4_TX_DP<66>")
		)
		(pad "P42" smd circle
			(at 16.150082 -10.450068)
			(size 0.4572 0.4572)
			(layers "F.Cu" "F.Mask" "F.Paste")
			(net "P5E_PEX3_STN4_TX_DN<66>")
		)
		(pad "P43" smd circle
			(at 17.100042 -10.450068)
			(size 0.4572 0.4572)
			(layers "F.Cu" "F.Mask" "F.Paste")
			(net "GND")
		)
		(pad "P44" smd circle
			(at 18.050002 -10.450068)
			(size 0.4572 0.4572)
			(layers "F.Cu" "F.Mask" "F.Paste")
			(net "GND")
		)
		(pad "P45" smd circle
			(at 18.999962 -10.450068)
			(size 0.4572 0.4572)
			(layers "F.Cu" "F.Mask" "F.Paste")
			(net "GND")
		)
		(pad "P46" smd circle
			(at 19.949922 -10.450068)
			(size 0.4572 0.4572)
			(layers "F.Cu" "F.Mask" "F.Paste")
			(net "GND")
		)
		(pad "P47" smd circle
			(at 20.899882 -10.450068)
			(size 0.4572 0.4572)
			(layers "F.Cu" "F.Mask" "F.Paste")
			(net "GND")
		)
		(pad "P48" smd circle
			(at 21.850096 -10.450068)
			(size 0.4572 0.4572)
			(layers "F.Cu" "F.Mask" "F.Paste")
			(net "P5E_PEX3_STN4_RX_DP<66>")
		)
		(pad "P49" smd circle
			(at 22.800056 -10.450068)
			(size 0.4572 0.4572)
			(layers "F.Cu" "F.Mask" "F.Paste")
			(net "P5E_PEX3_STN4_RX_DN<66>")
		)
		(pad "R1" smd circle
			(at -22.800056 -9.500108)
			(size 0.4572 0.4572)
			(layers "F.Cu" "F.Mask" "F.Paste")
			(net "GND")
		)
		(pad "R2" smd circle
			(at -21.850096 -9.500108)
			(size 0.4572 0.4572)
			(layers "F.Cu" "F.Mask" "F.Paste")
			(net "GND")
		)
		(pad "R3" smd circle
			(at -20.899882 -9.500108)
			(size 0.4572 0.4572)
			(layers "F.Cu" "F.Mask" "F.Paste")
			(net "P5E_PEX3_STN7_RX_DN<116>")
		)
		(pad "R4" smd circle
			(at -19.949922 -9.500108)
			(size 0.4572 0.4572)
			(layers "F.Cu" "F.Mask" "F.Paste")
			(net "P5E_PEX3_STN7_RX_DP<116>")
		)
		(pad "R5" smd circle
			(at -18.999962 -9.500108)
			(size 0.4572 0.4572)
			(layers "F.Cu" "F.Mask" "F.Paste")
			(net "GND")
		)
		(pad "R6" smd circle
			(at -18.050002 -9.500108)
			(size 0.4572 0.4572)
			(layers "F.Cu" "F.Mask" "F.Paste")
			(net "P5E_PEX3_STN7_TX_DN<116>")
		)
		(pad "R7" smd circle
			(at -17.100042 -9.500108)
			(size 0.4572 0.4572)
			(layers "F.Cu" "F.Mask" "F.Paste")
			(net "P5E_PEX3_STN7_TX_DP<116>")
		)
		(pad "R8" smd circle
			(at -16.150082 -9.500108)
			(size 0.4572 0.4572)
			(layers "F.Cu" "F.Mask" "F.Paste")
			(net "GND")
		)
		(pad "R9" smd circle
			(at -15.200122 -9.500108)
			(size 0.4572 0.4572)
			(layers "F.Cu" "F.Mask" "F.Paste")
			(net "GND")
		)
		(pad "R10" smd circle
			(at -14.249908 -9.500108)
			(size 0.4572 0.4572)
			(layers "F.Cu" "F.Mask" "F.Paste")
			(net "GND")
		)
		(pad "R11" smd circle
			(at -13.299948 -9.500108)
			(size 0.4572 0.4572)
			(layers "F.Cu" "F.Mask" "F.Paste")
			(net "GND")
		)
		(pad "R12" smd circle
			(at -12.349988 -9.500108)
			(size 0.4572 0.4572)
			(layers "F.Cu" "F.Mask" "F.Paste")
			(net "GND")
		)
		(pad "R13" smd circle
			(at -11.400028 -9.500108)
			(size 0.4572 0.4572)
			(layers "F.Cu" "F.Mask" "F.Paste")
			(net "GND")
		)
		(pad "R14" smd circle
			(at -10.450068 -9.500108)
			(size 0.4572 0.4572)
			(layers "F.Cu" "F.Mask" "F.Paste")
			(net "GND")
		)
		(pad "R15" smd circle
			(at -9.500108 -9.500108)
			(size 0.4572 0.4572)
			(layers "F.Cu" "F.Mask" "F.Paste")
			(net "GND")
		)
		(pad "R16" smd circle
			(at -8.549894 -9.500108)
			(size 0.4572 0.4572)
			(layers "F.Cu" "F.Mask" "F.Paste")
			(net "GND")
		)
	)
)
